(kicad_pcb
	(version 20260206)
	(generator "pcbnew")
	(generator_version "10.0")
	(general
		(thickness 1.6)
		(legacy_teardrops no)
	)
	(paper "A4")
	(title_block
		(title "Bryce Canyon_IOM_IOC_16318-2_OCP.brd")
		(comment 1 "Bryce Canyon / footprint 27 of 1605 (MEZZ1), pads 1-117 of 122")
	)
	(layers
		(0 "F.Cu" signal "TOP")
		(4 "In1.Cu" signal "L2GND")
		(6 "In2.Cu" signal "L3")
		(8 "In3.Cu" signal "L4VCC")
		(10 "In4.Cu" signal "L5VCC")
		(12 "In5.Cu" signal "L6")
		(14 "In6.Cu" signal "L7GND")
		(2 "B.Cu" signal "BOTTOM")
		(9 "F.Adhes" user "F.Adhesive")
		(11 "B.Adhes" user "B.Adhesive")
		(13 "F.Paste" user "Package Geometry/Pastemask Top")
		(15 "B.Paste" user "Package Geometry/Pastemask Bottom")
		(5 "F.SilkS" user "Ref Des/Silkscreen Top")
		(7 "B.SilkS" user "Ref Des/Silkscreen Bottom")
		(1 "F.Mask" user "Board Geometry/Soldermask Top")
		(3 "B.Mask" user "Board Geometry/Soldermask Bottom")
		(17 "Dwgs.User" user "User.Drawings")
		(19 "Cmts.User" user "User.Comments")
		(21 "Eco1.User" user "User.Eco1")
		(23 "Eco2.User" user "User.Eco2")
		(25 "Edge.Cuts" user "Board Geometry/Outline")
		(27 "Margin" user)
		(31 "F.CrtYd" user "Package Geometry/Place Bound Top")
		(29 "B.CrtYd" user "Package Geometry/Place Bound Bottom")
		(35 "F.Fab" user "Ref Des/Assembly Top")
		(33 "B.Fab" user "Ref Des/Assembly Bottom")
	)
	(footprint ""
		(layer "F.Cu")
		(at 77.700124 -72.55002 -90)
		(property "Reference" "MEZZ1"
			(at 0 0 270)
			(layer "F.SilkS")
			(hide yes)
			(effects
				(font
					(size 1.27 1.27)
				)
			)
		)
		(property "Value" "FCI-CONN120-GP-U1"
			(at -28.2321 -1.7018 270)
			(unlocked yes)
			(layer "F.Fab")
			(hide yes)
			(effects
				(font
					(size 1.016 1.016)
					(thickness 0.1524)
				)
			)
		)
		(property "Device Type" "61082-121402LF-U1"
			(at -28.2321 -3.2258 270)
			(unlocked yes)
			(layer "F.Fab")
			(hide yes)
			(effects
				(font
					(size 1.016 1.016)
					(thickness 0.1524)
				)
			)
		)
		(duplicate_pad_numbers_are_jumpers no)
		(pad "" np_thru_hole circle
			(at -26.100024 0 270)
			(size 0.254 0.254)
			(drill 0.8636)
			(layers "*.Cu" "*.Mask")
			(clearance 0.6604)
			(thermal_gap 0.6604)
		)
		(pad "" np_thru_hole circle
			(at 26.100024 0 270)
			(size 0.254 0.254)
			(drill 1.2192)
			(layers "*.Cu" "*.Mask")
			(clearance 0.8382)
			(thermal_gap 0.8382)
		)
		(pad "1" smd rect
			(at 23.599902 -2.22504 270)
			(size 0.508 2.0574)
			(layers "F.Cu" "F.Mask" "F.Paste")
			(net "MEZZA_PRSNT1_N")
		)
		(pad "2" smd rect
			(at 22.800056 -2.22504 270)
			(size 0.508 2.0574)
			(layers "F.Cu" "F.Mask" "F.Paste")
			(net "P5V_STBY")
		)
		(pad "3" smd rect
			(at 21.999956 -2.22504 270)
			(size 0.508 2.0574)
			(layers "F.Cu" "F.Mask" "F.Paste")
			(net "P5V_STBY")
		)
		(pad "4" smd rect
			(at 21.20011 -2.22504 270)
			(size 0.508 2.0574)
			(layers "F.Cu" "F.Mask" "F.Paste")
			(net "P5V_STBY")
		)
		(pad "5" smd rect
			(at 20.40001 -2.22504 270)
			(size 0.508 2.0574)
			(layers "F.Cu" "F.Mask" "F.Paste")
			(net "GND")
		)
		(pad "6" smd rect
			(at 19.59991 -2.22504 270)
			(size 0.508 2.0574)
			(layers "F.Cu" "F.Mask" "F.Paste")
			(net "GND")
		)
		(pad "7" smd rect
			(at 18.800064 -2.22504 270)
			(size 0.508 2.0574)
			(layers "F.Cu" "F.Mask" "F.Paste")
			(net "P3V3_STBY")
		)
		(pad "8" smd rect
			(at 17.999964 -2.22504 270)
			(size 0.508 2.0574)
			(layers "F.Cu" "F.Mask" "F.Paste")
			(net "GND")
		)
		(pad "9" smd rect
			(at 17.200118 -2.22504 270)
			(size 0.508 2.0574)
			(layers "F.Cu" "F.Mask" "F.Paste")
			(net "GND")
		)
		(pad "10" smd rect
			(at 16.400018 -2.22504 270)
			(size 0.508 2.0574)
			(layers "F.Cu" "F.Mask" "F.Paste")
			(net "P3V3")
		)
		(pad "11" smd rect
			(at 15.599918 -2.22504 270)
			(size 0.508 2.0574)
			(layers "F.Cu" "F.Mask" "F.Paste")
			(net "P3V3")
		)
		(pad "12" smd rect
			(at 14.800072 -2.22504 270)
			(size 0.508 2.0574)
			(layers "F.Cu" "F.Mask" "F.Paste")
			(net "P3V3")
		)
		(pad "13" smd rect
			(at 13.999972 -2.22504 270)
			(size 0.508 2.0574)
			(layers "F.Cu" "F.Mask" "F.Paste")
			(net "P3V3")
		)
		(pad "14" smd rect
			(at 13.200126 -2.22504 270)
			(size 0.508 2.0574)
			(layers "F.Cu" "F.Mask" "F.Paste")
			(net "NCSI_RCSDV_R")
		)
		(pad "15" smd rect
			(at 12.400026 -2.22504 270)
			(size 0.508 2.0574)
			(layers "F.Cu" "F.Mask" "F.Paste")
			(net "NCSI_RCLK")
		)
		(pad "16" smd rect
			(at 11.599926 -2.22504 270)
			(size 0.508 2.0574)
			(layers "F.Cu" "F.Mask" "F.Paste")
			(net "NCSI_TXEN_R")
		)
		(pad "17" smd rect
			(at 10.80008 -2.22504 270)
			(size 0.508 2.0574)
			(layers "F.Cu" "F.Mask" "F.Paste")
			(net "PCIE_COMP_TO_IOM_RST_4_R")
		)
		(pad "18" smd rect
			(at 9.99998 -2.22504 270)
			(size 0.508 2.0574)
			(layers "F.Cu" "F.Mask" "F.Paste")
			(net "I2C_MEZZ_OOB_SCL")
		)
		(pad "19" smd rect
			(at 9.19988 -2.22504 270)
			(size 0.508 2.0574)
			(layers "F.Cu" "F.Mask" "F.Paste")
			(net "I2C_MEZZ_OOB_SDA")
		)
		(pad "20" smd rect
			(at 8.400034 -2.22504 270)
			(size 0.508 2.0574)
			(layers "F.Cu" "F.Mask" "F.Paste")
			(net "GND")
		)
		(pad "21" smd rect
			(at 7.599934 -2.22504 270)
			(size 0.508 2.0574)
			(layers "F.Cu" "F.Mask" "F.Paste")
			(net "GND")
		)
		(pad "22" smd rect
			(at 6.800088 -2.22504 270)
			(size 0.508 2.0574)
			(layers "F.Cu" "F.Mask" "F.Paste")
			(net "NCSI_RXD0_R")
		)
		(pad "23" smd rect
			(at 5.999988 -2.22504 270)
			(size 0.508 2.0574)
			(layers "F.Cu" "F.Mask" "F.Paste")
			(net "NCSI_RXD1_R")
		)
		(pad "24" smd rect
			(at 5.199888 -2.22504 270)
			(size 0.508 2.0574)
			(layers "F.Cu" "F.Mask" "F.Paste")
			(net "GND")
		)
		(pad "25" smd rect
			(at 4.400042 -2.22504 270)
			(size 0.508 2.0574)
			(layers "F.Cu" "F.Mask" "F.Paste")
			(net "GND")
		)
		(pad "26" smd rect
			(at 3.599942 -2.22504 270)
			(size 0.508 2.0574)
			(layers "F.Cu" "F.Mask" "F.Paste")
			(net "Net_17")
		)
		(pad "27" smd rect
			(at 2.800096 -2.22504 270)
			(size 0.508 2.0574)
			(layers "F.Cu" "F.Mask" "F.Paste")
			(net "Net_16")
		)
		(pad "28" smd rect
			(at 1.999996 -2.22504 270)
			(size 0.508 2.0574)
			(layers "F.Cu" "F.Mask" "F.Paste")
			(net "GND")
		)
		(pad "29" smd rect
			(at 1.199896 -2.22504 270)
			(size 0.508 2.0574)
			(layers "F.Cu" "F.Mask" "F.Paste")
			(net "GND")
		)
		(pad "30" smd rect
			(at 0.40005 -2.22504 270)
			(size 0.508 2.0574)
			(layers "F.Cu" "F.Mask" "F.Paste")
			(net "PCIE_IOM_TO_COMP_16_DP")
		)
		(pad "31" smd rect
			(at -0.40005 -2.22504 270)
			(size 0.508 2.0574)
			(layers "F.Cu" "F.Mask" "F.Paste")
			(net "PCIE_IOM_TO_COMP_16_DN")
		)
		(pad "32" smd rect
			(at -1.199896 -2.22504 270)
			(size 0.508 2.0574)
			(layers "F.Cu" "F.Mask" "F.Paste")
			(net "GND")
		)
		(pad "33" smd rect
			(at -1.999996 -2.22504 270)
			(size 0.508 2.0574)
			(layers "F.Cu" "F.Mask" "F.Paste")
			(net "GND")
		)
		(pad "34" smd rect
			(at -2.800096 -2.22504 270)
			(size 0.508 2.0574)
			(layers "F.Cu" "F.Mask" "F.Paste")
			(net "PCIE_IOM_TO_COMP_17_DP")
		)
		(pad "35" smd rect
			(at -3.599942 -2.22504 270)
			(size 0.508 2.0574)
			(layers "F.Cu" "F.Mask" "F.Paste")
			(net "PCIE_IOM_TO_COMP_17_DN")
		)
		(pad "36" smd rect
			(at -4.400042 -2.22504 270)
			(size 0.508 2.0574)
			(layers "F.Cu" "F.Mask" "F.Paste")
			(net "GND")
		)
		(pad "37" smd rect
			(at -5.199888 -2.22504 270)
			(size 0.508 2.0574)
			(layers "F.Cu" "F.Mask" "F.Paste")
			(net "GND")
		)
		(pad "38" smd rect
			(at -5.999988 -2.22504 270)
			(size 0.508 2.0574)
			(layers "F.Cu" "F.Mask" "F.Paste")
			(net "PCIE_IOM_TO_COMP_18_DP")
		)
		(pad "39" smd rect
			(at -6.800088 -2.22504 270)
			(size 0.508 2.0574)
			(layers "F.Cu" "F.Mask" "F.Paste")
			(net "PCIE_IOM_TO_COMP_18_DN")
		)
		(pad "40" smd rect
			(at -7.599934 -2.22504 270)
			(size 0.508 2.0574)
			(layers "F.Cu" "F.Mask" "F.Paste")
			(net "GND")
		)
		(pad "41" smd rect
			(at -8.400034 -2.22504 270)
			(size 0.508 2.0574)
			(layers "F.Cu" "F.Mask" "F.Paste")
			(net "GND")
		)
		(pad "42" smd rect
			(at -9.19988 -2.22504 270)
			(size 0.508 2.0574)
			(layers "F.Cu" "F.Mask" "F.Paste")
			(net "PCIE_IOM_TO_COMP_19_DP")
		)
		(pad "43" smd rect
			(at -9.99998 -2.22504 270)
			(size 0.508 2.0574)
			(layers "F.Cu" "F.Mask" "F.Paste")
			(net "PCIE_IOM_TO_COMP_19_DN")
		)
		(pad "44" smd rect
			(at -10.80008 -2.22504 270)
			(size 0.508 2.0574)
			(layers "F.Cu" "F.Mask" "F.Paste")
			(net "GND")
		)
		(pad "45" smd rect
			(at -11.599926 -2.22504 270)
			(size 0.508 2.0574)
			(layers "F.Cu" "F.Mask" "F.Paste")
			(net "GND")
		)
		(pad "46" smd rect
			(at -12.400026 -2.22504 270)
			(size 0.508 2.0574)
			(layers "F.Cu" "F.Mask" "F.Paste")
			(net "PCIE_IOM_TO_COMP_20_DP")
		)
		(pad "47" smd rect
			(at -13.200126 -2.22504 270)
			(size 0.508 2.0574)
			(layers "F.Cu" "F.Mask" "F.Paste")
			(net "PCIE_IOM_TO_COMP_20_DN")
		)
		(pad "48" smd rect
			(at -13.999972 -2.22504 270)
			(size 0.508 2.0574)
			(layers "F.Cu" "F.Mask" "F.Paste")
			(net "GND")
		)
		(pad "49" smd rect
			(at -14.800072 -2.22504 270)
			(size 0.508 2.0574)
			(layers "F.Cu" "F.Mask" "F.Paste")
			(net "GND")
		)
		(pad "50" smd rect
			(at -15.599918 -2.22504 270)
			(size 0.508 2.0574)
			(layers "F.Cu" "F.Mask" "F.Paste")
			(net "PCIE_IOM_TO_COMP_21_DP")
		)
		(pad "51" smd rect
			(at -16.400018 -2.22504 270)
			(size 0.508 2.0574)
			(layers "F.Cu" "F.Mask" "F.Paste")
			(net "PCIE_IOM_TO_COMP_21_DN")
		)
		(pad "52" smd rect
			(at -17.200118 -2.22504 270)
			(size 0.508 2.0574)
			(layers "F.Cu" "F.Mask" "F.Paste")
			(net "GND")
		)
		(pad "53" smd rect
			(at -17.999964 -2.22504 270)
			(size 0.508 2.0574)
			(layers "F.Cu" "F.Mask" "F.Paste")
			(net "GND")
		)
		(pad "54" smd rect
			(at -18.800064 -2.22504 270)
			(size 0.508 2.0574)
			(layers "F.Cu" "F.Mask" "F.Paste")
			(net "PCIE_IOM_TO_COMP_22_DP")
		)
		(pad "55" smd rect
			(at -19.59991 -2.22504 270)
			(size 0.508 2.0574)
			(layers "F.Cu" "F.Mask" "F.Paste")
			(net "PCIE_IOM_TO_COMP_22_DN")
		)
		(pad "56" smd rect
			(at -20.40001 -2.22504 270)
			(size 0.508 2.0574)
			(layers "F.Cu" "F.Mask" "F.Paste")
			(net "GND")
		)
		(pad "57" smd rect
			(at -21.20011 -2.22504 270)
			(size 0.508 2.0574)
			(layers "F.Cu" "F.Mask" "F.Paste")
			(net "GND")
		)
		(pad "58" smd rect
			(at -21.999956 -2.22504 270)
			(size 0.508 2.0574)
			(layers "F.Cu" "F.Mask" "F.Paste")
			(net "PCIE_IOM_TO_COMP_23_DP")
		)
		(pad "59" smd rect
			(at -22.800056 -2.22504 270)
			(size 0.508 2.0574)
			(layers "F.Cu" "F.Mask" "F.Paste")
			(net "PCIE_IOM_TO_COMP_23_DN")
		)
		(pad "60" smd rect
			(at -23.599902 -2.22504 270)
			(size 0.508 2.0574)
			(layers "F.Cu" "F.Mask" "F.Paste")
			(net "GND")
		)
		(pad "61" smd rect
			(at 23.599902 2.22504 270)
			(size 0.508 2.0574)
			(layers "F.Cu" "F.Mask" "F.Paste")
			(net "P12V_STBY")
		)
		(pad "62" smd rect
			(at 22.800056 2.22504 270)
			(size 0.508 2.0574)
			(layers "F.Cu" "F.Mask" "F.Paste")
			(net "P12V_STBY")
		)
		(pad "63" smd rect
			(at 21.999956 2.22504 270)
			(size 0.508 2.0574)
			(layers "F.Cu" "F.Mask" "F.Paste")
			(net "P12V_STBY")
		)
		(pad "64" smd rect
			(at 21.20011 2.22504 270)
			(size 0.508 2.0574)
			(layers "F.Cu" "F.Mask" "F.Paste")
			(net "GND")
		)
		(pad "65" smd rect
			(at 20.40001 2.22504 270)
			(size 0.508 2.0574)
			(layers "F.Cu" "F.Mask" "F.Paste")
			(net "GND")
		)
		(pad "66" smd rect
			(at 19.59991 2.22504 270)
			(size 0.508 2.0574)
			(layers "F.Cu" "F.Mask" "F.Paste")
			(net "P3V3_STBY")
		)
		(pad "67" smd rect
			(at 18.800064 2.22504 270)
			(size 0.508 2.0574)
			(layers "F.Cu" "F.Mask" "F.Paste")
			(net "GND")
		)
		(pad "68" smd rect
			(at 17.999964 2.22504 270)
			(size 0.508 2.0574)
			(layers "F.Cu" "F.Mask" "F.Paste")
			(net "GND")
		)
		(pad "69" smd rect
			(at 17.200118 2.22504 270)
			(size 0.508 2.0574)
			(layers "F.Cu" "F.Mask" "F.Paste")
			(net "P3V3")
		)
		(pad "70" smd rect
			(at 16.400018 2.22504 270)
			(size 0.508 2.0574)
			(layers "F.Cu" "F.Mask" "F.Paste")
			(net "P3V3")
		)
		(pad "71" smd rect
			(at 15.599918 2.22504 270)
			(size 0.508 2.0574)
			(layers "F.Cu" "F.Mask" "F.Paste")
			(net "P3V3")
		)
		(pad "72" smd rect
			(at 14.800072 2.22504 270)
			(size 0.508 2.0574)
			(layers "F.Cu" "F.Mask" "F.Paste")
			(net "P3V3")
		)
		(pad "73" smd rect
			(at 13.999972 2.22504 270)
			(size 0.508 2.0574)
			(layers "F.Cu" "F.Mask" "F.Paste")
			(net "GND")
		)
		(pad "74" smd rect
			(at 13.200126 2.22504 270)
			(size 0.508 2.0574)
			(layers "F.Cu" "F.Mask" "F.Paste")
			(net "I2C_MEZZ_ALERT_R_N")
		)
		(pad "75" smd rect
			(at 12.400026 2.22504 270)
			(size 0.508 2.0574)
			(layers "F.Cu" "F.Mask" "F.Paste")
			(net "I2C_MEZZ_FRU_SENSOR_SCL")
		)
		(pad "76" smd rect
			(at 11.599926 2.22504 270)
			(size 0.508 2.0574)
			(layers "F.Cu" "F.Mask" "F.Paste")
			(net "I2C_MEZZ_FRU_SENSOR_SDA")
		)
		(pad "77" smd rect
			(at 10.80008 2.22504 270)
			(size 0.508 2.0574)
			(layers "F.Cu" "F.Mask" "F.Paste")
			(net "PCIE_WAKE_N")
		)
		(pad "78" smd rect
			(at 9.99998 2.22504 270)
			(size 0.508 2.0574)
			(layers "F.Cu" "F.Mask" "F.Paste")
			(net "NCSI_RX_ER_R")
		)
		(pad "79" smd rect
			(at 9.19988 2.22504 270)
			(size 0.508 2.0574)
			(layers "F.Cu" "F.Mask" "F.Paste")
			(net "GND")
		)
		(pad "80" smd rect
			(at 8.400034 2.22504 270)
			(size 0.508 2.0574)
			(layers "F.Cu" "F.Mask" "F.Paste")
			(net "NCSI_TXD0")
		)
		(pad "81" smd rect
			(at 7.599934 2.22504 270)
			(size 0.508 2.0574)
			(layers "F.Cu" "F.Mask" "F.Paste")
			(net "NCSI_TXD1")
		)
		(pad "82" smd rect
			(at 6.800088 2.22504 270)
			(size 0.508 2.0574)
			(layers "F.Cu" "F.Mask" "F.Paste")
			(net "GND")
		)
		(pad "83" smd rect
			(at 5.999988 2.22504 270)
			(size 0.508 2.0574)
			(layers "F.Cu" "F.Mask" "F.Paste")
			(net "GND")
		)
		(pad "84" smd rect
			(at 5.199888 2.22504 270)
			(size 0.508 2.0574)
			(layers "F.Cu" "F.Mask" "F.Paste")
			(net "PCIE_COMP_TO_IOM_CLK_4_DP")
		)
		(pad "85" smd rect
			(at 4.400042 2.22504 270)
			(size 0.508 2.0574)
			(layers "F.Cu" "F.Mask" "F.Paste")
			(net "PCIE_COMP_TO_IOM_CLK_4_DN")
		)
		(pad "86" smd rect
			(at 3.599942 2.22504 270)
			(size 0.508 2.0574)
			(layers "F.Cu" "F.Mask" "F.Paste")
			(net "GND")
		)
		(pad "87" smd rect
			(at 2.800096 2.22504 270)
			(size 0.508 2.0574)
			(layers "F.Cu" "F.Mask" "F.Paste")
			(net "GND")
		)
		(pad "88" smd rect
			(at 1.999996 2.22504 270)
			(size 0.508 2.0574)
			(layers "F.Cu" "F.Mask" "F.Paste")
			(net "PCIE_COMP_TO_IOM_16_DP")
		)
		(pad "89" smd rect
			(at 1.199896 2.22504 270)
			(size 0.508 2.0574)
			(layers "F.Cu" "F.Mask" "F.Paste")
			(net "PCIE_COMP_TO_IOM_16_DN")
		)
		(pad "90" smd rect
			(at 0.40005 2.22504 270)
			(size 0.508 2.0574)
			(layers "F.Cu" "F.Mask" "F.Paste")
			(net "GND")
		)
		(pad "91" smd rect
			(at -0.40005 2.22504 270)
			(size 0.508 2.0574)
			(layers "F.Cu" "F.Mask" "F.Paste")
			(net "GND")
		)
		(pad "92" smd rect
			(at -1.199896 2.22504 270)
			(size 0.508 2.0574)
			(layers "F.Cu" "F.Mask" "F.Paste")
			(net "PCIE_COMP_TO_IOM_17_DP")
		)
		(pad "93" smd rect
			(at -1.999996 2.22504 270)
			(size 0.508 2.0574)
			(layers "F.Cu" "F.Mask" "F.Paste")
			(net "PCIE_COMP_TO_IOM_17_DN")
		)
		(pad "94" smd rect
			(at -2.800096 2.22504 270)
			(size 0.508 2.0574)
			(layers "F.Cu" "F.Mask" "F.Paste")
			(net "GND")
		)
		(pad "95" smd rect
			(at -3.599942 2.22504 270)
			(size 0.508 2.0574)
			(layers "F.Cu" "F.Mask" "F.Paste")
			(net "GND")
		)
		(pad "96" smd rect
			(at -4.400042 2.22504 270)
			(size 0.508 2.0574)
			(layers "F.Cu" "F.Mask" "F.Paste")
			(net "PCIE_COMP_TO_IOM_18_DP")
		)
		(pad "97" smd rect
			(at -5.199888 2.22504 270)
			(size 0.508 2.0574)
			(layers "F.Cu" "F.Mask" "F.Paste")
			(net "PCIE_COMP_TO_IOM_18_DN")
		)
		(pad "98" smd rect
			(at -5.999988 2.22504 270)
			(size 0.508 2.0574)
			(layers "F.Cu" "F.Mask" "F.Paste")
			(net "GND")
		)
		(pad "99" smd rect
			(at -6.800088 2.22504 270)
			(size 0.508 2.0574)
			(layers "F.Cu" "F.Mask" "F.Paste")
			(net "GND")
		)
		(pad "100" smd rect
			(at -7.599934 2.22504 270)
			(size 0.508 2.0574)
			(layers "F.Cu" "F.Mask" "F.Paste")
			(net "PCIE_COMP_TO_IOM_19_DP")
		)
		(pad "101" smd rect
			(at -8.400034 2.22504 270)
			(size 0.508 2.0574)
			(layers "F.Cu" "F.Mask" "F.Paste")
			(net "PCIE_COMP_TO_IOM_19_DN")
		)
		(pad "102" smd rect
			(at -9.19988 2.22504 270)
			(size 0.508 2.0574)
			(layers "F.Cu" "F.Mask" "F.Paste")
			(net "GND")
		)
		(pad "103" smd rect
			(at -9.99998 2.22504 270)
			(size 0.508 2.0574)
			(layers "F.Cu" "F.Mask" "F.Paste")
			(net "GND")
		)
		(pad "104" smd rect
			(at -10.80008 2.22504 270)
			(size 0.508 2.0574)
			(layers "F.Cu" "F.Mask" "F.Paste")
			(net "PCIE_COMP_TO_IOM_20_DP")
		)
		(pad "105" smd rect
			(at -11.599926 2.22504 270)
			(size 0.508 2.0574)
			(layers "F.Cu" "F.Mask" "F.Paste")
			(net "PCIE_COMP_TO_IOM_20_DN")
		)
		(pad "106" smd rect
			(at -12.400026 2.22504 270)
			(size 0.508 2.0574)
			(layers "F.Cu" "F.Mask" "F.Paste")
			(net "GND")
		)
		(pad "107" smd rect
			(at -13.200126 2.22504 270)
			(size 0.508 2.0574)
			(layers "F.Cu" "F.Mask" "F.Paste")
			(net "GND")
		)
		(pad "108" smd rect
			(at -13.999972 2.22504 270)
			(size 0.508 2.0574)
			(layers "F.Cu" "F.Mask" "F.Paste")
			(net "PCIE_COMP_TO_IOM_21_DP")
		)
		(pad "109" smd rect
			(at -14.800072 2.22504 270)
			(size 0.508 2.0574)
			(layers "F.Cu" "F.Mask" "F.Paste")
			(net "PCIE_COMP_TO_IOM_21_DN")
		)
		(pad "110" smd rect
			(at -15.599918 2.22504 270)
			(size 0.508 2.0574)
			(layers "F.Cu" "F.Mask" "F.Paste")
			(net "GND")
		)
		(pad "111" smd rect
			(at -16.400018 2.22504 270)
			(size 0.508 2.0574)
			(layers "F.Cu" "F.Mask" "F.Paste")
			(net "GND")
		)
		(pad "112" smd rect
			(at -17.200118 2.22504 270)
			(size 0.508 2.0574)
			(layers "F.Cu" "F.Mask" "F.Paste")
			(net "PCIE_COMP_TO_IOM_22_DP")
		)
		(pad "113" smd rect
			(at -17.999964 2.22504 270)
			(size 0.508 2.0574)
			(layers "F.Cu" "F.Mask" "F.Paste")
			(net "PCIE_COMP_TO_IOM_22_DN")
		)
		(pad "114" smd rect
			(at -18.800064 2.22504 270)
			(size 0.508 2.0574)
			(layers "F.Cu" "F.Mask" "F.Paste")
			(net "GND")
		)
		(pad "115" smd rect
			(at -19.59991 2.22504 270)
			(size 0.508 2.0574)
			(layers "F.Cu" "F.Mask" "F.Paste")
			(net "GND")
		)
	)
)
